FILE_TYPE=LIBRARY_PARTS;
primitive 'SCONN3_21291035BR2';
  pin
    '3':
      PIN_NUMBER='(3)';
      BIDIRECTIONAL='TRUE';
      INPUT_LOAD='(-0.01,0.01)';
      OUTPUT_LOAD='(1.0,-1.0)';
    '2':
      PIN_NUMBER='(2)';
      BIDIRECTIONAL='TRUE';
      INPUT_LOAD='(-0.01,0.01)';
      OUTPUT_LOAD='(1.0,-1.0)';
    '1':
      PIN_NUMBER='(1)';
      BIDIRECTIONAL='TRUE';
      INPUT_LOAD='(-0.01,0.01)';
      OUTPUT_LOAD='(1.0,-1.0)';
  end_pin;
  body
    PART_NAME='SCONN3_21291035BR2';
    BODY_NAME='SCONN3_21291035BR2';
    PHYS_DES_PREFIX='J';
    CLASS='IO';
  end_body;
end_primitive;

END.
